(kicad_pcb
	(version 20241229)
	(generator "pcbnew")
	(generator_version "9.0")
	(general
		(thickness 1.711)
		(legacy_teardrops no)
	)
	(paper "A4")
	(title_block
		(title "Antmicro Baseboard for Jetson AGX Thor")
		(date "2026-02-18")
		(rev "1.1.0")
		(company "Antmicro Ltd")
		(comment 1 "www.antmicro.com")
		(comment 9 "footprint 710 of 1170 (J18), pads 555-564 of 564")
	)
	(layers
		(0 "F.Cu" signal)
		(4 "In1.Cu" signal)
		(6 "In2.Cu" signal)
		(8 "In3.Cu" signal)
		(10 "In4.Cu" jumper)
		(12 "In5.Cu" signal)
		(14 "In6.Cu" signal)
		(16 "In7.Cu" signal)
		(18 "In8.Cu" signal)
		(2 "B.Cu" signal)
		(9 "F.Adhes" user "F.Adhesive")
		(11 "B.Adhes" user "B.Adhesive")
		(13 "F.Paste" user)
		(15 "B.Paste" user)
		(5 "F.SilkS" user "F.Silkscreen")
		(7 "B.SilkS" user "B.Silkscreen")
		(1 "F.Mask" user)
		(3 "B.Mask" user)
		(17 "Dwgs.User" user "User.Drawings")
		(19 "Cmts.User" user "User.Comments")
		(21 "Eco1.User" user "User.Eco1")
		(23 "Eco2.User" user "User.Eco2")
		(25 "Edge.Cuts" user)
		(27 "Margin" user)
		(31 "F.CrtYd" user "F.Courtyard")
		(29 "B.CrtYd" user "B.Courtyard")
		(35 "F.Fab" user)
		(33 "B.Fab" user)
	)
	(footprint "antmicro-footprints:ASP-208571-01_mounting_holes"
		(locked yes)
		(layer "B.Cu")
		(at 77.680532 103.71 90)
		(property "Reference" "J18"
			(at -25.89 11.119468 270)
			(layer "B.SilkS")
			(effects
				(font
					(size 0.7 0.7)
					(thickness 0.15)
				)
				(justify left bottom mirror)
			)
		)
		(property "Value" "ASP-208571-01_mounting_holes"
			(at -15.05 -10.885 270)
			(layer "B.Fab")
			(effects
				(font
					(size 0.7 0.7)
					(thickness 0.15)
				)
				(justify left bottom mirror)
			)
		)
		(property "Datasheet" "https://suddendocs.samtec.com/prints/asp-208571-01-mkt.pdf"
			(at 0 0 270)
			(layer "B.Fab")
			(hide yes)
			(effects
				(font
					(size 1.27 1.27)
					(thickness 0.15)
				)
				(justify mirror)
			)
		)
		(property "Description" "FMC connector"
			(at 0 0 270)
			(layer "B.Fab")
			(hide yes)
			(effects
				(font
					(size 1.27 1.27)
					(thickness 0.15)
				)
				(justify mirror)
			)
		)
		(property "MPN" "ASP-208571-01"
			(at 0 0 90)
			(unlocked yes)
			(layer "B.Fab")
			(hide yes)
			(effects
				(font
					(size 1 1)
					(thickness 0.15)
				)
				(justify mirror)
			)
		)
		(property "Manufacturer" "Samtec"
			(at 0 0 90)
			(unlocked yes)
			(layer "B.Fab")
			(hide yes)
			(effects
				(font
					(size 1 1)
					(thickness 0.15)
				)
				(justify mirror)
			)
		)
		(property "Author" "Antmicro"
			(at 0 0 90)
			(unlocked yes)
			(layer "B.Fab")
			(hide yes)
			(effects
				(font
					(size 1 1)
					(thickness 0.15)
				)
				(justify mirror)
			)
		)
		(property "License" "Apache-2.0"
			(at 0 0 90)
			(unlocked yes)
			(layer "B.Fab")
			(hide yes)
			(effects
				(font
					(size 1 1)
					(thickness 0.15)
				)
				(justify mirror)
			)
		)
		(sheetname "/Expansion connector/")
		(sheetfile "expansion_connector.kicad_sch")
		(attr smd)
		(pad "Z31" smd circle
			(at -13.335 6.985 90)
			(size 0.64 0.64)
			(layers "B.Cu" "B.Mask")
			(net 1 "GND")
			(pinfunction "Z31")
			(pintype "passive")
		)
		(pad "Z32" smd circle
			(at -14.605 6.985 90)
			(size 0.64 0.64)
			(layers "B.Cu" "B.Mask")
			(net 851 "/Expansion connector/PCIe_{C2x1}.CLK-")
			(pinfunction "Z32")
			(pintype "passive")
		)
		(pad "Z33" smd circle
			(at -15.875 6.985 90)
			(size 0.64 0.64)
			(layers "B.Cu" "B.Mask")
			(net 843 "/Expansion connector/PCIe_{C2x1}.CLK+")
			(pinfunction "Z33")
			(pintype "passive")
		)
		(pad "Z34" smd circle
			(at -17.145 6.985 90)
			(size 0.64 0.64)
			(layers "B.Cu" "B.Mask")
			(net 1 "GND")
			(pinfunction "Z34")
			(pintype "passive")
		)
		(pad "Z35" smd circle
			(at -18.415 6.985 90)
			(size 0.64 0.64)
			(layers "B.Cu" "B.Mask")
			(net 1 "GND")
			(pinfunction "Z35")
			(pintype "passive")
		)
		(pad "Z36" smd circle
			(at -19.685 6.985 90)
			(size 0.64 0.64)
			(layers "B.Cu" "B.Mask")
			(net 479 "/Expansion connector/PET0_C2_N")
			(pinfunction "Z36")
			(pintype "passive")
		)
		(pad "Z37" smd circle
			(at -20.955 6.985 90)
			(size 0.64 0.64)
			(layers "B.Cu" "B.Mask")
			(net 476 "/Expansion connector/PET0_C2_P")
			(pinfunction "Z37")
			(pintype "passive")
		)
		(pad "Z38" smd circle
			(at -22.225 6.985 90)
			(size 0.64 0.64)
			(layers "B.Cu" "B.Mask")
			(net 1 "GND")
			(pinfunction "Z38")
			(pintype "passive")
		)
		(pad "Z39" smd circle
			(at -23.495 6.985 90)
			(size 0.64 0.64)
			(layers "B.Cu" "B.Mask")
			(net 1 "GND")
			(pinfunction "Z39")
			(pintype "passive")
		)
		(pad "Z40" smd circle
			(at -24.765 6.985 90)
			(size 0.64 0.64)
			(layers "B.Cu" "B.Mask")
			(net 297 "/Expansion connector/+3V3_FMC")
			(pinfunction "Z40")
			(pintype "passive")
		)
	)
)
